(kicad_pcb
	(version 20260206)
	(generator "pcbnew")
	(generator_version "10.0")
	(general
		(thickness 1.6)
		(legacy_teardrops no)
	)
	(paper "A4")
	(title_block
		(title "peb — Lightning_PEB_BRD.brd")
		(comment 1 "Lightning (Wiwynn / Facebook NVMe JBOF) / footprints 1427-1433 of 2563")
	)
	(layers
		(0 "F.Cu" signal "TOP")
		(4 "In1.Cu" signal "L2GND")
		(6 "In2.Cu" signal "L3")
		(8 "In3.Cu" signal "L4VCC")
		(10 "In4.Cu" signal "L5VCC")
		(12 "In5.Cu" signal "L6")
		(14 "In6.Cu" signal "L7GND")
		(2 "B.Cu" signal "BOTTOM")
		(9 "F.Adhes" user "F.Adhesive")
		(11 "B.Adhes" user "B.Adhesive")
		(13 "F.Paste" user "Package Geometry/Pastemask Top")
		(15 "B.Paste" user "Package Geometry/Pastemask Bottom")
		(5 "F.SilkS" user "Ref Des/Silkscreen Top")
		(7 "B.SilkS" user "Ref Des/Silkscreen Bottom")
		(1 "F.Mask" user "Board Geometry/Soldermask Top")
		(3 "B.Mask" user "Board Geometry/Soldermask Bottom")
		(17 "Dwgs.User" user "User.Drawings")
		(19 "Cmts.User" user "User.Comments")
		(21 "Eco1.User" user "User.Eco1")
		(23 "Eco2.User" user "User.Eco2")
		(25 "Edge.Cuts" user "Board Geometry/Outline")
		(27 "Margin" user)
		(31 "F.CrtYd" user "Package Geometry/Place Bound Top")
		(29 "B.CrtYd" user "Package Geometry/Place Bound Bottom")
		(35 "F.Fab" user "Ref Des/Assembly Top")
		(33 "B.Fab" user "Ref Des/Assembly Bottom")
	)
	(footprint ""
		(layer "F.Cu")
		(at 78.843124 -183.235092)
		(property "Reference" "R7973"
			(at 0 0 0)
			(layer "F.SilkS")
			(hide yes)
			(effects
				(font
					(size 1.27 1.27)
				)
			)
		)
		(property "Value" "0R2J-2-GP"
			(at 0.064008 -3.993896 0)
			(unlocked yes)
			(layer "F.Fab")
			(hide yes)
			(effects
				(font
					(size 1.016 1.016)
					(thickness 0.1524)
				)
			)
		)
		(property "Device Type" "R402H16"
			(at 0.064008 -5.517896 0)
			(unlocked yes)
			(layer "F.Fab")
			(hide yes)
			(effects
				(font
					(size 1.016 1.016)
					(thickness 0.1524)
				)
			)
		)
		(duplicate_pad_numbers_are_jumpers no)
		(fp_line
			(start -0.508 -0.9398)
			(end -0.508 0.9398)
			(stroke
				(width 0.1524)
				(type default)
			)
			(layer "F.SilkS")
		)
		(fp_line
			(start 0.508 -0.9398)
			(end -0.508 -0.9398)
			(stroke
				(width 0.1524)
				(type default)
			)
			(layer "F.SilkS")
		)
		(fp_rect
			(start -0.508 0.9398)
			(end 0.508 -0.9398)
			(stroke
				(width 0)
				(type default)
			)
			(fill no)
			(layer "F.CrtYd")
		)
		(fp_rect
			(start -0.508 0.9398)
			(end 0.508 -0.9398)
			(stroke
				(width 0)
				(type default)
			)
			(fill no)
			(layer "F.Fab")
		)
		(pad "1" smd custom
			(at 0 -0.4445)
			(size 0.1397 0.1397)
			(layers "F.Cu" "F.Mask" "F.Paste")
			(net "SSD_PERST#5")
			(options
				(clearance outline)
				(anchor circle)
			)
			(primitives
				(gr_poly
					(pts
						(arc
							(start -0.1778 -0.2794)
							(mid -0.249642 -0.249642)
							(end -0.2794 -0.1778)
						)
						(arc
							(start -0.2794 0.1778)
							(mid -0.249642 0.249642)
							(end -0.1778 0.2794)
						)
						(arc
							(start 0.1778 0.2794)
							(mid 0.249642 0.249642)
							(end 0.2794 0.1778)
						)
						(arc
							(start 0.2794 -0.1778)
							(mid 0.249642 -0.249642)
							(end 0.1778 -0.2794)
						)
					)
					(width 0)
					(fill yes)
				)
			)
		)
		(pad "2" smd custom
			(at 0 0.4445)
			(size 0.1397 0.1397)
			(layers "F.Cu" "F.Mask" "F.Paste")
			(net "SSD_PERST#5_R")
			(options
				(clearance outline)
				(anchor circle)
			)
			(primitives
				(gr_poly
					(pts
						(arc
							(start -0.1778 -0.2794)
							(mid -0.249642 -0.249642)
							(end -0.2794 -0.1778)
						)
						(arc
							(start -0.2794 0.1778)
							(mid -0.249642 0.249642)
							(end -0.1778 0.2794)
						)
						(arc
							(start 0.1778 0.2794)
							(mid 0.249642 0.249642)
							(end 0.2794 0.1778)
						)
						(arc
							(start 0.2794 -0.1778)
							(mid 0.249642 -0.249642)
							(end 0.1778 -0.2794)
						)
					)
					(width 0)
					(fill yes)
				)
			)
		)
	)
	(footprint ""
		(layer "F.Cu")
		(at 192.9384 -25.0952 90)
		(property "Reference" "R836"
			(at 0 0 90)
			(layer "F.SilkS")
			(hide yes)
			(effects
				(font
					(size 1.27 1.27)
				)
			)
		)
		(property "Value" "4K7R2F-GP"
			(at 0.064008 -3.993896 90)
			(unlocked yes)
			(layer "F.Fab")
			(hide yes)
			(effects
				(font
					(size 1.016 1.016)
					(thickness 0.1524)
				)
			)
		)
		(property "Device Type" "R402H16"
			(at 0.064008 -5.517896 90)
			(unlocked yes)
			(layer "F.Fab")
			(hide yes)
			(effects
				(font
					(size 1.016 1.016)
					(thickness 0.1524)
				)
			)
		)
		(duplicate_pad_numbers_are_jumpers no)
		(fp_line
			(start 0.508 -0.9398)
			(end -0.508 -0.9398)
			(stroke
				(width 0.1524)
				(type default)
			)
			(layer "F.SilkS")
		)
		(fp_line
			(start -0.508 -0.9398)
			(end -0.508 0.9398)
			(stroke
				(width 0.1524)
				(type default)
			)
			(layer "F.SilkS")
		)
		(fp_rect
			(start -0.508 0.9398)
			(end 0.508 -0.9398)
			(stroke
				(width 0)
				(type default)
			)
			(fill no)
			(layer "F.CrtYd")
		)
		(fp_rect
			(start -0.508 0.9398)
			(end 0.508 -0.9398)
			(stroke
				(width 0)
				(type default)
			)
			(fill no)
			(layer "F.Fab")
		)
		(pad "1" smd custom
			(at 0 -0.4445 90)
			(size 0.1397 0.1397)
			(layers "F.Cu" "F.Mask" "F.Paste")
			(net "GND")
			(options
				(clearance outline)
				(anchor circle)
			)
			(primitives
				(gr_poly
					(pts
						(arc
							(start -0.1778 -0.2794)
							(mid -0.249642 -0.249642)
							(end -0.2794 -0.1778)
						)
						(arc
							(start -0.2794 0.1778)
							(mid -0.249642 0.249642)
							(end -0.1778 0.2794)
						)
						(arc
							(start 0.1778 0.2794)
							(mid 0.249642 0.249642)
							(end 0.2794 0.1778)
						)
						(arc
							(start 0.2794 -0.1778)
							(mid 0.249642 -0.249642)
							(end 0.1778 -0.2794)
						)
					)
					(width 0)
					(fill yes)
				)
			)
		)
		(pad "2" smd custom
			(at 0 0.4445 90)
			(size 0.1397 0.1397)
			(layers "F.Cu" "F.Mask" "F.Paste")
			(net "U56_A1")
			(options
				(clearance outline)
				(anchor circle)
			)
			(primitives
				(gr_poly
					(pts
						(arc
							(start -0.1778 -0.2794)
							(mid -0.249642 -0.249642)
							(end -0.2794 -0.1778)
						)
						(arc
							(start -0.2794 0.1778)
							(mid -0.249642 0.249642)
							(end -0.1778 0.2794)
						)
						(arc
							(start 0.1778 0.2794)
							(mid 0.249642 0.249642)
							(end 0.2794 0.1778)
						)
						(arc
							(start 0.2794 -0.1778)
							(mid 0.249642 -0.249642)
							(end 0.1778 -0.2794)
						)
					)
					(width 0)
					(fill yes)
				)
			)
		)
	)
	(footprint ""
		(layer "F.Cu")
		(at 346.456 -51.689 90)
		(property "Reference" "PC217"
			(at 0 0 90)
			(layer "F.SilkS")
			(hide yes)
			(effects
				(font
					(size 1.27 1.27)
				)
			)
		)
		(property "Value" "SC22U25V6KX-GP-U"
			(at -2.860802 -5.279644 90)
			(unlocked yes)
			(layer "F.Fab")
			(hide yes)
			(effects
				(font
					(size 1.016 1.016)
					(thickness 0.1524)
				)
			)
		)
		(property "Device Type" "C1206-TO0D3H75"
			(at -2.860802 -6.803644 90)
			(unlocked yes)
			(layer "F.Fab")
			(hide yes)
			(effects
				(font
					(size 1.016 1.016)
					(thickness 0.1524)
				)
			)
		)
		(duplicate_pad_numbers_are_jumpers no)
		(fp_line
			(start 1.3081 -2.3749)
			(end 1.3081 2.3749)
			(stroke
				(width 0.1524)
				(type default)
			)
			(layer "F.SilkS")
		)
		(fp_line
			(start -1.3081 -2.3749)
			(end 1.3081 -2.3749)
			(stroke
				(width 0.1524)
				(type default)
			)
			(layer "F.SilkS")
		)
		(fp_line
			(start 1.3081 2.3749)
			(end -1.3081 2.3749)
			(stroke
				(width 0.1524)
				(type default)
			)
			(layer "F.SilkS")
		)
		(fp_line
			(start -1.3081 2.3749)
			(end -1.3081 -2.3749)
			(stroke
				(width 0.1524)
				(type default)
			)
			(layer "F.SilkS")
		)
		(fp_rect
			(start -0.8001 1.6002)
			(end 0.8001 -1.6002)
			(stroke
				(width 0)
				(type default)
			)
			(fill no)
			(layer "F.CrtYd")
		)
		(fp_poly
			(pts
				(xy -1.5621 2.4511) (xy -1.5621 1.6002) (xy 0.8001 1.6002) (xy 0.8001 -1.6002) (xy -0.8001 -1.6002)
				(xy -0.8001 1.5875) (xy -1.5621 1.5875) (xy -1.5621 -2.4511) (xy 1.5621 -2.4511) (xy 1.5621 2.4511)
			)
			(stroke
				(width 0)
				(type default)
			)
			(fill no)
			(layer "F.CrtYd")
		)
		(fp_rect
			(start -1.5621 2.4511)
			(end 1.5621 -2.4511)
			(stroke
				(width 0)
				(type default)
			)
			(fill no)
			(layer "F.Fab")
		)
		(pad "1" smd rect
			(at 0 -1.392936 90)
			(size 2.1082 1.4478)
			(layers "F.Cu" "F.Mask" "F.Paste")
			(net "P0V9_E_VIN")
		)
		(pad "2" smd rect
			(at 0 1.392936 90)
			(size 2.1082 1.4478)
			(layers "F.Cu" "F.Mask" "F.Paste")
			(net "GND")
		)
	)
	(footprint ""
		(layer "F.Cu")
		(at 208.4578 -16.2306 90)
		(property "Reference" "Q6"
			(at 0 0 90)
			(layer "F.SilkS")
			(hide yes)
			(effects
				(font
					(size 1.27 1.27)
				)
			)
		)
		(property "Value" "2N7002K-1-GP"
			(at 0.127 -8.9662 90)
			(unlocked yes)
			(layer "F.Fab")
			(hide yes)
			(effects
				(font
					(size 1.016 1.016)
					(thickness 0.1524)
				)
			)
		)
		(property "Device Type" "SOT23DGS2D4H44"
			(at 0.127 -10.4902 90)
			(unlocked yes)
			(layer "F.Fab")
			(hide yes)
			(effects
				(font
					(size 1.016 1.016)
					(thickness 0.1524)
				)
			)
		)
		(duplicate_pad_numbers_are_jumpers no)
		(fp_line
			(start 1.651 -1.778)
			(end -1.651 -1.778)
			(stroke
				(width 0.1524)
				(type default)
			)
			(layer "F.SilkS")
		)
		(fp_line
			(start -1.651 -1.778)
			(end -1.651 1.778)
			(stroke
				(width 0.1524)
				(type default)
			)
			(layer "F.SilkS")
		)
		(fp_line
			(start 1.651 1.778)
			(end 1.651 -1.778)
			(stroke
				(width 0.1524)
				(type default)
			)
			(layer "F.SilkS")
		)
		(fp_line
			(start -1.651 1.778)
			(end 1.651 1.778)
			(stroke
				(width 0.1524)
				(type default)
			)
			(layer "F.SilkS")
		)
		(fp_poly
			(pts
				(xy -1.778 1.8796) (xy -1.778 -1.8796) (xy 1.778 -1.8796) (xy 1.778 1.8796)
			)
			(stroke
				(width 0)
				(type default)
			)
			(fill no)
			(layer "F.CrtYd")
		)
		(fp_poly
			(pts
				(xy -1.778 1.8796) (xy -1.778 -1.8796) (xy 1.778 -1.8796) (xy 1.778 1.8796)
			)
			(stroke
				(width 0)
				(type default)
			)
			(fill no)
			(layer "F.Fab")
		)
		(pad "D" smd custom
			(at 0 -0.9525 90)
			(size 0.1905 0.1905)
			(layers "F.Cu" "F.Mask" "F.Paste")
			(net "LED_PWR_N_ON")
			(options
				(clearance outline)
				(anchor circle)
			)
			(primitives
				(gr_poly
					(pts
						(arc
							(start -0.1778 0.5715)
							(mid -0.321484 0.511984)
							(end -0.381 0.3683)
						)
						(arc
							(start -0.381 -0.3683)
							(mid -0.321484 -0.511984)
							(end -0.1778 -0.5715)
						)
						(arc
							(start 0.1778 -0.5715)
							(mid 0.321484 -0.511984)
							(end 0.381 -0.3683)
						)
						(arc
							(start 0.381 0.3683)
							(mid 0.321484 0.511984)
							(end 0.1778 0.5715)
						)
					)
					(width 0)
					(fill yes)
				)
			)
		)
		(pad "G" smd custom
			(at -0.98425 0.9525 90)
			(size 0.1905 0.1905)
			(layers "F.Cu" "F.Mask" "F.Paste")
			(net "BMC_ID_LED_R")
			(options
				(clearance outline)
				(anchor circle)
			)
			(primitives
				(gr_poly
					(pts
						(arc
							(start -0.1778 0.5715)
							(mid -0.321484 0.511984)
							(end -0.381 0.3683)
						)
						(arc
							(start -0.381 -0.3683)
							(mid -0.321484 -0.511984)
							(end -0.1778 -0.5715)
						)
						(arc
							(start 0.1778 -0.5715)
							(mid 0.321484 -0.511984)
							(end 0.381 -0.3683)
						)
						(arc
							(start 0.381 0.3683)
							(mid 0.321484 0.511984)
							(end 0.1778 0.5715)
						)
					)
					(width 0)
					(fill yes)
				)
			)
		)
		(pad "S" smd custom
			(at 0.98425 0.9525 90)
			(size 0.1905 0.1905)
			(layers "F.Cu" "F.Mask" "F.Paste")
			(net "GND")
			(options
				(clearance outline)
				(anchor circle)
			)
			(primitives
				(gr_poly
					(pts
						(arc
							(start -0.1778 0.5715)
							(mid -0.321484 0.511984)
							(end -0.381 0.3683)
						)
						(arc
							(start -0.381 -0.3683)
							(mid -0.321484 -0.511984)
							(end -0.1778 -0.5715)
						)
						(arc
							(start 0.1778 -0.5715)
							(mid 0.321484 -0.511984)
							(end 0.381 -0.3683)
						)
						(arc
							(start 0.381 0.3683)
							(mid 0.321484 0.511984)
							(end 0.1778 0.5715)
						)
					)
					(width 0)
					(fill yes)
				)
			)
		)
	)
	(footprint ""
		(layer "F.Cu")
		(at 220.345 -5.588 180)
		(property "Reference" "R454"
			(at 0 0 180)
			(layer "F.SilkS")
			(hide yes)
			(effects
				(font
					(size 1.27 1.27)
				)
			)
		)
		(property "Value" "0R2J-2-GP"
			(at 0.064008 -3.993896 180)
			(unlocked yes)
			(layer "F.Fab")
			(hide yes)
			(effects
				(font
					(size 1.016 1.016)
					(thickness 0.1524)
				)
			)
		)
		(property "Device Type" "R402H16"
			(at 0.064008 -5.517896 180)
			(unlocked yes)
			(layer "F.Fab")
			(hide yes)
			(effects
				(font
					(size 1.016 1.016)
					(thickness 0.1524)
				)
			)
		)
		(duplicate_pad_numbers_are_jumpers no)
		(fp_line
			(start 0.508 -0.9398)
			(end -0.508 -0.9398)
			(stroke
				(width 0.1524)
				(type default)
			)
			(layer "F.SilkS")
		)
		(fp_line
			(start -0.508 -0.9398)
			(end -0.508 0.9398)
			(stroke
				(width 0.1524)
				(type default)
			)
			(layer "F.SilkS")
		)
		(fp_rect
			(start -0.508 0.9398)
			(end 0.508 -0.9398)
			(stroke
				(width 0)
				(type default)
			)
			(fill no)
			(layer "F.CrtYd")
		)
		(fp_rect
			(start -0.508 0.9398)
			(end 0.508 -0.9398)
			(stroke
				(width 0)
				(type default)
			)
			(fill no)
			(layer "F.Fab")
		)
		(pad "1" smd custom
			(at 0 -0.4445 180)
			(size 0.1397 0.1397)
			(layers "F.Cu" "F.Mask" "F.Paste")
			(net "BMC_UART_SWITCH_1")
			(options
				(clearance outline)
				(anchor circle)
			)
			(primitives
				(gr_poly
					(pts
						(arc
							(start -0.1778 -0.2794)
							(mid -0.249642 -0.249642)
							(end -0.2794 -0.1778)
						)
						(arc
							(start -0.2794 0.1778)
							(mid -0.249642 0.249642)
							(end -0.1778 0.2794)
						)
						(arc
							(start 0.1778 0.2794)
							(mid 0.249642 0.249642)
							(end 0.2794 0.1778)
						)
						(arc
							(start 0.2794 -0.1778)
							(mid 0.249642 -0.249642)
							(end 0.1778 -0.2794)
						)
					)
					(width 0)
					(fill yes)
				)
			)
		)
		(pad "2" smd custom
			(at 0 0.4445 180)
			(size 0.1397 0.1397)
			(layers "F.Cu" "F.Mask" "F.Paste")
			(net "BMC_CONSOLE_LED0_R")
			(options
				(clearance outline)
				(anchor circle)
			)
			(primitives
				(gr_poly
					(pts
						(arc
							(start -0.1778 -0.2794)
							(mid -0.249642 -0.249642)
							(end -0.2794 -0.1778)
						)
						(arc
							(start -0.2794 0.1778)
							(mid -0.249642 0.249642)
							(end -0.1778 0.2794)
						)
						(arc
							(start 0.1778 0.2794)
							(mid 0.249642 0.249642)
							(end 0.2794 0.1778)
						)
						(arc
							(start 0.2794 -0.1778)
							(mid 0.249642 -0.249642)
							(end 0.1778 -0.2794)
						)
					)
					(width 0)
					(fill yes)
				)
			)
		)
	)
	(footprint ""
		(layer "F.Cu")
		(at 85.70214 -74.71664 180)
		(property "Reference" "R423"
			(at 0 0 180)
			(layer "F.SilkS")
			(hide yes)
			(effects
				(font
					(size 1.27 1.27)
				)
			)
		)
		(property "Value" "2K2R2J-2-GP"
			(at 0.064008 -3.993896 180)
			(unlocked yes)
			(layer "F.Fab")
			(hide yes)
			(effects
				(font
					(size 1.016 1.016)
					(thickness 0.1524)
				)
			)
		)
		(property "Device Type" "R402H16"
			(at 0.064008 -5.517896 180)
			(unlocked yes)
			(layer "F.Fab")
			(hide yes)
			(effects
				(font
					(size 1.016 1.016)
					(thickness 0.1524)
				)
			)
		)
		(duplicate_pad_numbers_are_jumpers no)
		(fp_line
			(start 0.508 -0.9398)
			(end -0.508 -0.9398)
			(stroke
				(width 0.1524)
				(type default)
			)
			(layer "F.SilkS")
		)
		(fp_line
			(start -0.508 -0.9398)
			(end -0.508 0.9398)
			(stroke
				(width 0.1524)
				(type default)
			)
			(layer "F.SilkS")
		)
		(fp_rect
			(start -0.508 0.9398)
			(end 0.508 -0.9398)
			(stroke
				(width 0)
				(type default)
			)
			(fill no)
			(layer "F.CrtYd")
		)
		(fp_rect
			(start -0.508 0.9398)
			(end 0.508 -0.9398)
			(stroke
				(width 0)
				(type default)
			)
			(fill no)
			(layer "F.Fab")
		)
		(pad "1" smd custom
			(at 0 -0.4445 180)
			(size 0.1397 0.1397)
			(layers "F.Cu" "F.Mask" "F.Paste")
			(net "SEC_SPI_HOLD_N")
			(options
				(clearance outline)
				(anchor circle)
			)
			(primitives
				(gr_poly
					(pts
						(arc
							(start -0.1778 -0.2794)
							(mid -0.249642 -0.249642)
							(end -0.2794 -0.1778)
						)
						(arc
							(start -0.2794 0.1778)
							(mid -0.249642 0.249642)
							(end -0.1778 0.2794)
						)
						(arc
							(start 0.1778 0.2794)
							(mid 0.249642 0.249642)
							(end 0.2794 0.1778)
						)
						(arc
							(start 0.2794 -0.1778)
							(mid 0.249642 -0.249642)
							(end 0.1778 -0.2794)
						)
					)
					(width 0)
					(fill yes)
				)
			)
		)
		(pad "2" smd custom
			(at 0 0.4445 180)
			(size 0.1397 0.1397)
			(layers "F.Cu" "F.Mask" "F.Paste")
			(net "P3V3_STBY")
			(options
				(clearance outline)
				(anchor circle)
			)
			(primitives
				(gr_poly
					(pts
						(arc
							(start -0.1778 -0.2794)
							(mid -0.249642 -0.249642)
							(end -0.2794 -0.1778)
						)
						(arc
							(start -0.2794 0.1778)
							(mid -0.249642 0.249642)
							(end -0.1778 0.2794)
						)
						(arc
							(start 0.1778 0.2794)
							(mid 0.249642 0.249642)
							(end 0.2794 0.1778)
						)
						(arc
							(start 0.2794 -0.1778)
							(mid 0.249642 -0.249642)
							(end 0.1778 -0.2794)
						)
					)
					(width 0)
					(fill yes)
				)
			)
		)
	)
	(footprint ""
		(layer "F.Cu")
		(at 192.9384 -26.1366 -90)
		(property "Reference" "R824"
			(at 0 0 270)
			(layer "F.SilkS")
			(hide yes)
			(effects
				(font
					(size 1.27 1.27)
				)
			)
		)
		(property "Value" "4K7R2F-GP"
			(at 0.064008 -3.993896 270)
			(unlocked yes)
			(layer "F.Fab")
			(hide yes)
			(effects
				(font
					(size 1.016 1.016)
					(thickness 0.1524)
				)
			)
		)
		(property "Device Type" "R402H16"
			(at 0.064008 -5.517896 270)
			(unlocked yes)
			(layer "F.Fab")
			(hide yes)
			(effects
				(font
					(size 1.016 1.016)
					(thickness 0.1524)
				)
			)
		)
		(duplicate_pad_numbers_are_jumpers no)
		(fp_line
			(start -0.508 -0.9398)
			(end -0.508 0.9398)
			(stroke
				(width 0.1524)
				(type default)
			)
			(layer "F.SilkS")
		)
		(fp_line
			(start 0.508 -0.9398)
			(end -0.508 -0.9398)
			(stroke
				(width 0.1524)
				(type default)
			)
			(layer "F.SilkS")
		)
		(fp_rect
			(start -0.508 0.9398)
			(end 0.508 -0.9398)
			(stroke
				(width 0)
				(type default)
			)
			(fill no)
			(layer "F.CrtYd")
		)
		(fp_rect
			(start -0.508 0.9398)
			(end 0.508 -0.9398)
			(stroke
				(width 0)
				(type default)
			)
			(fill no)
			(layer "F.Fab")
		)
		(pad "1" smd custom
			(at 0 -0.4445 270)
			(size 0.1397 0.1397)
			(layers "F.Cu" "F.Mask" "F.Paste")
			(net "U56_A1")
			(options
				(clearance outline)
				(anchor circle)
			)
			(primitives
				(gr_poly
					(pts
						(arc
							(start -0.1778 -0.2794)
							(mid -0.249642 -0.249642)
							(end -0.2794 -0.1778)
						)
						(arc
							(start -0.2794 0.1778)
							(mid -0.249642 0.249642)
							(end -0.1778 0.2794)
						)
						(arc
							(start 0.1778 0.2794)
							(mid 0.249642 0.249642)
							(end 0.2794 0.1778)
						)
						(arc
							(start 0.2794 -0.1778)
							(mid 0.249642 -0.249642)
							(end 0.1778 -0.2794)
						)
					)
					(width 0)
					(fill yes)
				)
			)
		)
		(pad "2" smd custom
			(at 0 0.4445 270)
			(size 0.1397 0.1397)
			(layers "F.Cu" "F.Mask" "F.Paste")
			(net "P3V3_STBY")
			(options
				(clearance outline)
				(anchor circle)
			)
			(primitives
				(gr_poly
					(pts
						(arc
							(start -0.1778 -0.2794)
							(mid -0.249642 -0.249642)
							(end -0.2794 -0.1778)
						)
						(arc
							(start -0.2794 0.1778)
							(mid -0.249642 0.249642)
							(end -0.1778 0.2794)
						)
						(arc
							(start 0.1778 0.2794)
							(mid 0.249642 0.249642)
							(end 0.2794 0.1778)
						)
						(arc
							(start 0.2794 -0.1778)
							(mid 0.249642 -0.249642)
							(end 0.1778 -0.2794)
						)
					)
					(width 0)
					(fill yes)
				)
			)
		)
	)
)
